# BASEBOARD_FAB2 (Tioga Pass) — schematic netlist excerpt (pin names and nets, part order shuffled) for the footprints in the layout excerpt that follows; sources: Cadence DE-HDL packaged netlist, KiCad conversion of Wiwynn_Tioga_Pass_MB.brd

C4B8  CAP  1000PF 50V 10% X7R  pkg 0402LF  page 234 : A = PWRGD_PVPP_KLM_R ; B = GND
R9G26  RES  100.0K 1% CHIP  pkg 0402  page 169 : A = A_P3V_BAT_SCALED ; B = GND
RT8  RES  0 5.0% CHIP  pkg 0603  page 227 : A = VR_PVDDQ_KLM_PH2_BOOT ; B = VR_PVDDQ_KLM_PH2_BOOT_R

(kicad_pcb
	(version 20260206)
	(generator "pcbnew")
	(generator_version "10.0")
	(general
		(thickness 1.6)
		(legacy_teardrops no)
	)
	(paper "A4")
	(title_block
		(title "Wiwynn_Tioga_Pass_MB.brd")
		(comment 1 "Tioga Pass / footprints 2267-2269 of 4770")
	)
	(layers
		(0 "F.Cu" signal "TOP")
		(4 "In1.Cu" signal "L2GND")
		(6 "In2.Cu" signal "L3")
		(8 "In3.Cu" signal "L4GND")
		(10 "In4.Cu" signal "L5")
		(12 "In5.Cu" signal "L6GND")
		(14 "In6.Cu" signal "L7VCC")
		(16 "In7.Cu" signal "L8VCC")
		(18 "In8.Cu" signal "L9GND")
		(20 "In9.Cu" signal "L10")
		(22 "In10.Cu" signal "L11GND")
		(24 "In11.Cu" signal "L12")
		(26 "In12.Cu" signal "L13GND")
		(2 "B.Cu" signal "BOTTOM")
		(9 "F.Adhes" user "F.Adhesive")
		(11 "B.Adhes" user "B.Adhesive")
		(13 "F.Paste" user "Package Geometry/Pastemask Top")
		(15 "B.Paste" user "Package Geometry/Pastemask Bottom")
		(5 "F.SilkS" user "Ref Des/Silkscreen Top")
		(7 "B.SilkS" user "Ref Des/Silkscreen Bottom")
		(1 "F.Mask" user "Board Geometry/Soldermask Top")
		(3 "B.Mask" user "Board Geometry/Soldermask Bottom")
		(17 "Dwgs.User" user "User.Drawings")
		(19 "Cmts.User" user "User.Comments")
		(21 "Eco1.User" user "User.Eco1")
		(23 "Eco2.User" user "User.Eco2")
		(25 "Edge.Cuts" user "Board Geometry/Outline")
		(27 "Margin" user)
		(31 "F.CrtYd" user "Package Geometry/Place Bound Top")
		(29 "B.CrtYd" user "Package Geometry/Place Bound Bottom")
		(35 "F.Fab" user "Ref Des/Assembly Top")
		(33 "B.Fab" user "Ref Des/Assembly Bottom")
	)
	(footprint ""
		(layer "F.Cu")
		(at -3.901694 -148.286978 90)
		(property "Reference" "RT8"
			(at 1.01473 0.656336 0)
			(unlocked yes)
			(layer "F.SilkS")
			(effects
				(font
					(size 0.4064 0.254)
					(thickness 0.1524)
				)
			)
		)
		(property "Value" ""
			(at 0 0 90)
			(layer "F.Fab")
			(effects
				(font
					(size 1.27 1.27)
				)
			)
		)
		(duplicate_pad_numbers_are_jumpers no)
		(fp_poly
			(pts
				(xy -0.4953 -0.2032) (xy 0.4953 -0.2032) (xy 0.4953 1.6002) (xy -0.4953 1.6002)
			)
			(stroke
				(width 0)
				(type default)
			)
			(fill no)
			(layer "F.CrtYd")
		)
		(fp_line
			(start 0.4953 -0.2032)
			(end 0.4953 1.6002)
			(stroke
				(width 0.1)
				(type default)
			)
			(layer "F.Fab")
		)
		(fp_line
			(start -0.4953 -0.2032)
			(end 0.4953 -0.2032)
			(stroke
				(width 0.1)
				(type default)
			)
			(layer "F.Fab")
		)
		(fp_line
			(start 0.4953 1.6002)
			(end -0.4953 1.6002)
			(stroke
				(width 0.1)
				(type default)
			)
			(layer "F.Fab")
		)
		(fp_line
			(start -0.4953 1.6002)
			(end -0.4953 -0.2032)
			(stroke
				(width 0.1)
				(type default)
			)
			(layer "F.Fab")
		)
		(pad "1" smd rect
			(at 0 0 90)
			(size 0.762 0.889)
			(layers "F.Cu" "F.Mask" "F.Paste")
			(net "VR_PVDDQ_KLM_PH2_BOOT")
		)
		(pad "2" smd rect
			(at 0 1.397 90)
			(size 0.762 0.889)
			(layers "F.Cu" "F.Mask" "F.Paste")
			(net "VR_PVDDQ_KLM_PH2_BOOT_R")
		)
		(zone
			(layer "F.Cu")
			(hatch none 0.5)
			(connect_pads
				(clearance 0)
			)
			(min_thickness 0.25)
			(keepout
				(tracks allowed)
				(vias not_allowed)
				(pads allowed)
				(copperpour not_allowed)
				(footprints allowed)
			)
			(placement
				(enabled no)
				(sheetname "")
			)
			(fill
				(thermal_gap 0.5)
				(thermal_bridge_width 0.5)
				(island_removal_mode 0)
			)
			(polygon
				(pts
					(xy -2.949194 -148.667978) (xy -3.457194 -148.667978) (xy -3.457194 -147.905978) (xy -2.949194 -147.905978)
				)
			)
		)
		(zone
			(layer "F.Cu")
			(hatch none 0.5)
			(connect_pads
				(clearance 0)
			)
			(min_thickness 0.25)
			(keepout
				(tracks not_allowed)
				(vias allowed)
				(pads allowed)
				(copperpour not_allowed)
				(footprints allowed)
			)
			(placement
				(enabled no)
				(sheetname "")
			)
			(fill
				(thermal_gap 0.5)
				(thermal_bridge_width 0.5)
				(island_removal_mode 0)
			)
			(polygon
				(pts
					(xy -2.949194 -147.905978) (xy -2.949194 -148.667978) (xy -3.457194 -148.667978) (xy -3.457194 -147.905978)
				)
			)
		)
	)
	(footprint ""
		(layer "F.Cu")
		(at 465.328 -0.254 -90)
		(property "Reference" "R9G26"
			(at 0 0 270)
			(layer "F.SilkS")
			(hide yes)
			(effects
				(font
					(size 1.27 1.27)
				)
			)
		)
		(property "Value" ""
			(at 0 0 270)
			(layer "F.Fab")
			(effects
				(font
					(size 1.27 1.27)
				)
			)
		)
		(duplicate_pad_numbers_are_jumpers no)
		(fp_poly
			(pts
				(xy -0.2794 -0.1016) (xy 0.2794 -0.1016) (xy 0.2794 0.9906) (xy -0.2794 0.9906)
			)
			(stroke
				(width 0)
				(type default)
			)
			(fill no)
			(layer "F.CrtYd")
		)
		(fp_line
			(start -0.2794 0.9906)
			(end 0.2794 0.9906)
			(stroke
				(width 0.1)
				(type default)
			)
			(layer "F.Fab")
		)
		(fp_line
			(start 0.2794 0.9906)
			(end 0.2794 -0.1016)
			(stroke
				(width 0.1)
				(type default)
			)
			(layer "F.Fab")
		)
		(fp_line
			(start -0.2794 -0.1016)
			(end -0.2794 0.9906)
			(stroke
				(width 0.1)
				(type default)
			)
			(layer "F.Fab")
		)
		(fp_line
			(start 0.2794 -0.1016)
			(end -0.2794 -0.1016)
			(stroke
				(width 0.1)
				(type default)
			)
			(layer "F.Fab")
		)
		(pad "1" smd rect
			(at 0 0 270)
			(size 0.508 0.508)
			(layers "F.Cu" "F.Mask" "F.Paste")
			(net "A_P3V_BAT_SCALED")
		)
		(pad "2" smd rect
			(at 0 0.889 270)
			(size 0.508 0.508)
			(layers "F.Cu" "F.Mask" "F.Paste")
			(net "GND")
		)
		(zone
			(layer "F.Cu")
			(hatch none 0.5)
			(connect_pads
				(clearance 0)
			)
			(min_thickness 0.25)
			(keepout
				(tracks not_allowed)
				(vias allowed)
				(pads allowed)
				(copperpour not_allowed)
				(footprints allowed)
			)
			(placement
				(enabled no)
				(sheetname "")
			)
			(fill
				(thermal_gap 0.5)
				(thermal_bridge_width 0.5)
				(island_removal_mode 0)
			)
			(polygon
				(pts
					(xy 464.693 -0.508) (xy 464.693 0) (xy 465.074 0) (xy 465.074 -0.508)
				)
			)
		)
		(zone
			(layer "F.Cu")
			(hatch none 0.5)
			(connect_pads
				(clearance 0)
			)
			(min_thickness 0.25)
			(keepout
				(tracks allowed)
				(vias not_allowed)
				(pads allowed)
				(copperpour not_allowed)
				(footprints allowed)
			)
			(placement
				(enabled no)
				(sheetname "")
			)
			(fill
				(thermal_gap 0.5)
				(thermal_bridge_width 0.5)
				(island_removal_mode 0)
			)
			(polygon
				(pts
					(xy 465.074 -0.508) (xy 465.074 0) (xy 464.693 0) (xy 464.693 -0.508)
				)
			)
		)
	)
	(footprint ""
		(layer "F.Cu")
		(at 178.943 -131.7625)
		(property "Reference" "C4B8"
			(at 0 0 0)
			(layer "F.SilkS")
			(hide yes)
			(effects
				(font
					(size 1.27 1.27)
				)
			)
		)
		(property "Value" ""
			(at 0 0 0)
			(layer "F.Fab")
			(effects
				(font
					(size 1.27 1.27)
				)
			)
		)
		(duplicate_pad_numbers_are_jumpers no)
		(fp_poly
			(pts
				(xy 0.3048 -0.1016) (xy 0.3048 0.9906) (xy -0.3048 0.9906) (xy -0.3048 -0.1016)
			)
			(stroke
				(width 0)
				(type default)
			)
			(fill no)
			(layer "F.CrtYd")
		)
		(fp_line
			(start -0.3048 -0.1016)
			(end -0.3048 0.9906)
			(stroke
				(width 0.1)
				(type default)
			)
			(layer "F.Fab")
		)
		(fp_line
			(start -0.3048 0.9906)
			(end 0.3048 0.9906)
			(stroke
				(width 0.1)
				(type default)
			)
			(layer "F.Fab")
		)
		(fp_line
			(start 0.3048 -0.1016)
			(end -0.3048 -0.1016)
			(stroke
				(width 0.1)
				(type default)
			)
			(layer "F.Fab")
		)
		(fp_line
			(start 0.3048 0.9906)
			(end 0.3048 -0.1016)
			(stroke
				(width 0.1)
				(type default)
			)
			(layer "F.Fab")
		)
		(pad "1" smd rect
			(at 0 0)
			(size 0.508 0.508)
			(layers "F.Cu" "F.Mask" "F.Paste")
			(net "PWRGD_PVPP_KLM_R")
		)
		(pad "2" smd rect
			(at 0 0.889)
			(size 0.508 0.508)
			(layers "F.Cu" "F.Mask" "F.Paste")
			(net "GND")
		)
		(zone
			(layer "F.Cu")
			(hatch none 0.5)
			(connect_pads
				(clearance 0)
			)
			(min_thickness 0.25)
			(keepout
				(tracks allowed)
				(vias not_allowed)
				(pads allowed)
				(copperpour not_allowed)
				(footprints allowed)
			)
			(placement
				(enabled no)
				(sheetname "")
			)
			(fill
				(thermal_gap 0.5)
				(thermal_bridge_width 0.5)
				(island_removal_mode 0)
			)
			(polygon
				(pts
					(xy 178.689 -131.5085) (xy 179.197 -131.5085) (xy 179.197 -131.1275) (xy 178.689 -131.1275)
				)
			)
		)
		(zone
			(layer "F.Cu")
			(hatch none 0.5)
			(connect_pads
				(clearance 0)
			)
			(min_thickness 0.25)
			(keepout
				(tracks not_allowed)
				(vias allowed)
				(pads allowed)
				(copperpour not_allowed)
				(footprints allowed)
			)
			(placement
				(enabled no)
				(sheetname "")
			)
			(fill
				(thermal_gap 0.5)
				(thermal_bridge_width 0.5)
				(island_removal_mode 0)
			)
			(polygon
				(pts
					(xy 178.689 -131.1275) (xy 179.197 -131.1275) (xy 179.197 -131.5085) (xy 178.689 -131.5085)
				)
			)
		)
	)
)
